# S9S_MB_2U (Grand Teton) — schematic parts with pin connectivity, parts 1594–1594 of 6093; source: Cadence DE-HDL packaged netlist (pstxprt.dat, pstxnet.dat, pstchip.dat)

J1  SCONN288_ADR50017P130CC  SCONN288_ADR50017-P130CC IO  pkg DDR288S_1-1VXB  page 82
  1  VIN_BULK0  POWER  = P12V_S3_AUX_CPU0_NVDIMM
  2  RFU0  TRI  = TP_CHA_CPU0_DIMM1_FRU_0
  3  VIN_MGMT  POWER  = P3V3_AUX
  4  HSCL  IN  = I3C_SPD_DDRABCD_CPU0_LVC1_SCL_R
  5  HSDA  BI  = I3C_SPD_DDRABCD_CPU0_LVC1_SDA
  6  VSS0  POWER  = GND
  7  DQ0_A  BI  = M_A_CPU0_SA_DQ<0>
  8  VSS1  POWER  = GND
  9  DQ1_A  BI  = M_A_CPU0_SA_DQ<1>
  10  VSS2  POWER  = GND
  11  DQS0_A_T  BI  = M_A_CPU0_SA_DQS_DP<0>
  12  DQS0_A_C  BI  = M_A_CPU0_SA_DQS_DN<0>
  13  VSS3  POWER  = GND
  14  DQ4_A  BI  = M_A_CPU0_SA_DQ<4>
  15  VSS4  POWER  = GND
  16  DQ5_A  BI  = M_A_CPU0_SA_DQ<5>
  17  VSS5  POWER  = GND
  18  DQ8_A  BI  = M_A_CPU0_SA_DQ<8>
  19  VSS6  POWER  = GND
  20  DQ9_A  BI  = M_A_CPU0_SA_DQ<9>
  21  VSS7  POWER  = GND
  22  DQS1_A_T  BI  = M_A_CPU0_SA_DQS_DP<1>
  23  DQS1_A_C  BI  = M_A_CPU0_SA_DQS_DN<1>
  24  VSS8  POWER  = GND
  25  DQ12_A  BI  = M_A_CPU0_SA_DQ<12>
  26  VSS9  POWER  = GND
  27  DQ13_A  BI  = M_A_CPU0_SA_DQ<13>
  28  VSS10  POWER  = GND
  29  DQ16_A  BI  = M_A_CPU0_SA_DQ<16>
  30  VSS11  POWER  = GND
  31  DQ17_A  BI  = M_A_CPU0_SA_DQ<17>
  32  VSS12  POWER  = GND
  33  DQS2_A_T  BI  = M_A_CPU0_SA_DQS_DP<2>
  34  DQS2_A_C  BI  = M_A_CPU0_SA_DQS_DN<2>
  35  VSS13  POWER  = GND
  36  DQ20_A  BI  = M_A_CPU0_SA_DQ<20>
  37  VSS14  POWER  = GND
  38  DQ21_A  BI  = M_A_CPU0_SA_DQ<21>
  39  VSS15  POWER  = GND
  40  DQ24_A  BI  = M_A_CPU0_SA_DQ<24>
  41  VSS16  POWER  = GND
  42  DQ25_A  BI  = M_A_CPU0_SA_DQ<25>
  43  VSS17  POWER  = GND
  44  DQS3_A_T  BI  = M_A_CPU0_SA_DQS_DP<3>
  45  DQS3_A_C  BI  = M_A_CPU0_SA_DQS_DN<3>
  46  VSS18  POWER  = GND
  47  DQ28_A  BI  = M_A_CPU0_SA_DQ<28>
  48  VSS19  POWER  = GND
  49  DQ29_A  BI  = M_A_CPU0_SA_DQ<29>
  50  VSS20  POWER  = GND
  51  CB0_A  BI  = M_A_CPU0_SA_CB<0>
  52  VSS21  POWER  = GND
  53  CB1_A  BI  = M_A_CPU0_SA_CB<1>
  54  VSS22  POWER  = GND
  55  DQS4_A_T  BI  = M_A_CPU0_SA_DQS_DP<4>
  56  DQS4_A_C  BI  = M_A_CPU0_SA_DQS_DN<4>
  57  VSS23  POWER  = GND
  58  CB4_A  BI  = M_A_CPU0_SA_CB<4>
  59  VSS24  POWER  = GND
  60  CB5_A  BI  = M_A_CPU0_SA_CB<5>
  61  VSS25  POWER  = GND
  62  ALERT_N  OUT  = M_A_CPU0_ALERT_N
  63  VSS26  POWER  = GND
  64  CS0_A_N  IN  = M_A_CPU0_SA_CS_N<0>
  65  VSS27  POWER  = GND
  66  CA0_A  IN  = M_A_CPU0_SA_CA<0>
  67  VSS28  POWER  = GND
  68  CA2_A  IN  = M_A_CPU0_SA_CA<2>
  69  VSS29  POWER  = GND
  70  CA4_A  IN  = M_A_CPU0_SA_CA<4>
  71  VSS30  POWER  = GND
  72  CA6_A  IN  = M_A_CPU0_SA_CA<6>
  73  VSS31  POWER  = GND
  74  PAR_A  IN  = M_A_CPU0_SA_PAR
  75  VSS32  POWER  = GND
  76  CA0_B  IN  = M_A_CPU0_SB_CA<0>
  77  VSS33  POWER  = GND
  78  CA2_B  IN  = M_A_CPU0_SB_CA<2>
  79  VSS34  POWER  = GND
  80  CA4_B  IN  = M_A_CPU0_SB_CA<4>
  81  VSS35  POWER  = GND
  82  CA6_B  IN  = M_A_CPU0_SB_CA<6>
  83  VSS36  POWER  = GND
  84  CS0_B_N  IN  = M_A_CPU0_SB_CS_N<0>
  85  VSS37  POWER  = GND
  86  \lbd||rsp_a_n\  OUT  = M_A_CPU0_SA_RSP<0>
  87  \lbs||rsp_b_n\  OUT  = M_A_CPU0_SB_RSP<0>
  88  VSS38  POWER  = GND
  89  CB4_B  BI  = M_A_CPU0_SB_CB<4>
  90  VSS39  POWER  = GND
  91  CB5_B  BI  = M_A_CPU0_SB_CB<5>
  92  VSS40  POWER  = GND
  93  \dqs9_b_t||tdqs9_b_t||dbi4_b_n\  BI  = M_A_CPU0_SB_DQS_DP<9>
  94  \dqs9_b_c||tdqs9_b_c\  BI  = M_A_CPU0_SB_DQS_DN<9>
  95  VSS41  POWER  = GND
  96  CB0_B  BI  = M_A_CPU0_SB_CB<0>
  97  VSS42  POWER  = GND
  98  CB1_B  BI  = M_A_CPU0_SB_CB<1>
  99  VSS43  POWER  = GND
  100  DQ0_B  BI  = M_A_CPU0_SB_DQ<0>
  101  VSS44  POWER  = GND
  102  DQ1_B  BI  = M_A_CPU0_SB_DQ<1>
  103  VSS45  POWER  = GND
  104  DQS0_B_T  BI  = M_A_CPU0_SB_DQS_DP<0>
  105  DQS0_B_C  BI  = M_A_CPU0_SB_DQS_DN<0>
  106  VSS46  POWER  = GND
  107  DQ4_B  BI  = M_A_CPU0_SB_DQ<4>
  108  VSS47  POWER  = GND
  109  DQ5_B  BI  = M_A_CPU0_SB_DQ<5>
  110  VSS48  POWER  = GND
  111  DQ8_B  BI  = M_A_CPU0_SB_DQ<8>
  112  VSS49  POWER  = GND
  113  DQ9_B  BI  = M_A_CPU0_SB_DQ<9>
  114  VSS50  POWER  = GND
  115  DQS1_B_T  BI  = M_A_CPU0_SB_DQS_DP<1>
  116  DQS1_B_C  BI  = M_A_CPU0_SB_DQS_DN<1>
  117  VSS51  POWER  = GND
  118  DQ12_B  BI  = M_A_CPU0_SB_DQ<12>
  119  VSS52  POWER  = GND
  120  DQ13_B  BI  = M_A_CPU0_SB_DQ<13>
  121  VSS53  POWER  = GND
  122  DQ16_B  BI  = M_A_CPU0_SB_DQ<16>
  123  VSS54  POWER  = GND
  124  DQ17_B  BI  = M_A_CPU0_SB_DQ<17>
  125  VSS55  POWER  = GND
  126  DQS2_B_T  BI  = M_A_CPU0_SB_DQS_DP<2>
  127  DQS2_B_C  BI  = M_A_CPU0_SB_DQS_DN<2>
  128  VSS56  POWER  = GND
  129  DQ20_B  BI  = M_A_CPU0_SB_DQ<20>
  130  VSS57  POWER  = GND
  131  DQ21_B  BI  = M_A_CPU0_SB_DQ<21>
  132  VSS58  POWER  = GND
  133  DQ24_B  BI  = M_A_CPU0_SB_DQ<24>
  134  VSS59  POWER  = GND
  135  DQ25_B  BI  = M_A_CPU0_SB_DQ<25>
  136  VSS60  POWER  = GND
  137  DQS3_B_T  BI  = M_A_CPU0_SB_DQS_DP<3>
  138  DQS3_B_C  BI  = M_A_CPU0_SB_DQS_DN<3>
  139  VSS61  POWER  = GND
  140  DQ28_B  BI  = M_A_CPU0_SB_DQ<28>
  141  VSS62  POWER  = GND
  142  DQ29_B  BI  = M_A_CPU0_SB_DQ<29>
  143  VSS63  POWER  = GND
  144  RFU1  TRI  = TP_CHA_CPU0_DIMM1_FRU_1
  145  VIN_BULK1  POWER  = P12V_S3_AUX_CPU0_NVDIMM
  146  VIN_BULK2  POWER  = P12V_S3_AUX_CPU0_NVDIMM
  147  \pwr_good||fail_n\  BI  = PWRGD_CHA_CPU0_DIMM1
  148  HSA  IN  = PD_CHA_CPU0_DIMM1_SAA
  149  RFU2  TRI  = TP_CHA_CPU0_DIMM1_FRU_2
  150  RFU3  TRI  = TP_CHA_CPU0_DIMM1_FRU_3
  151  VSS64  POWER  = GND
  152  DQ2_A  BI  = M_A_CPU0_SA_DQ<2>
  153  VSS65  POWER  = GND
  154  DQ3_A  BI  = M_A_CPU0_SA_DQ<3>
  155  VSS66  POWER  = GND
  156  \dqs5_a_c||tdqs5_a_c||dqs5_a_t||tdqs5_a_t\  BI  = M_A_CPU0_SA_DQS_DN<5>
  157  \dqs5_a_t||tdqs5_a_t\  BI  = M_A_CPU0_SA_DQS_DP<5>
  158  VSS67  POWER  = GND
  159  DQ6_A  BI  = M_A_CPU0_SA_DQ<6>
  160  VSS68  POWER  = GND
  161  DQ7_A  BI  = M_A_CPU0_SA_DQ<7>
  162  VSS69  POWER  = GND
  163  DQ10_A  BI  = M_A_CPU0_SA_DQ<10>
  164  VSS70  POWER  = GND
  165  DQ11_A  BI  = M_A_CPU0_SA_DQ<11>
  166  VSS71  POWER  = GND
  167  \dqs6_a_c||tdqs6_a_c||dqs6_a_t||tdqs6_a_t\  BI  = M_A_CPU0_SA_DQS_DN<6>
  168  \dqs6_a_t||tdqs6_a_t\  BI  = M_A_CPU0_SA_DQS_DP<6>
  169  VSS72  POWER  = GND
  170  DQ14_A  BI  = M_A_CPU0_SA_DQ<14>
  171  VSS73  POWER  = GND
  172  DQ15_A  BI  = M_A_CPU0_SA_DQ<15>
  173  VSS74  POWER  = GND
  174  DQ18_A  BI  = M_A_CPU0_SA_DQ<18>
  175  VSS75  POWER  = GND
  176  DQ19_A  BI  = M_A_CPU0_SA_DQ<19>
  177  VSS76  POWER  = GND
  178  \dqs7_a_c||tdqs7_a_c\  BI  = M_A_CPU0_SA_DQS_DN<7>
  179  \dqs7_a_t||tdqs7_a_t\  BI  = M_A_CPU0_SA_DQS_DP<7>
  180  VSS77  POWER  = GND
  181  DQ22_A  BI  = M_A_CPU0_SA_DQ<22>
  182  VSS78  POWER  = GND
  183  DQ23_A  BI  = M_A_CPU0_SA_DQ<23>
  184  VSS79  POWER  = GND
  185  DQ26_A  BI  = M_A_CPU0_SA_DQ<26>
  186  VSS80  POWER  = GND
  187  DQ27_A  BI  = M_A_CPU0_SA_DQ<27>
  188  VSS81  POWER  = GND
  189  \dqs8_a_c||tdqs8_a_c\  BI  = M_A_CPU0_SA_DQS_DN<8>
  190  \dqs8_a_t||tdqs8_a_t\  BI  = M_A_CPU0_SA_DQS_DP<8>
  191  VSS82  POWER  = GND
  192  DQ30_A  BI  = M_A_CPU0_SA_DQ<30>
  193  VSS83  POWER  = GND
  194  DQ31_A  BI  = M_A_CPU0_SA_DQ<31>
  195  VSS84  POWER  = GND
  196  CB2_A  BI  = M_A_CPU0_SA_CB<2>
  197  VSS85  POWER  = GND
  198  CB3_A  BI  = M_A_CPU0_SA_CB<3>
  199  VSS86  POWER  = GND
  200  \dqs9_a_c||tdqs9_a_c\  BI  = M_A_CPU0_SA_DQS_DN<9>
  201  \dqs9_a_t||tdqs9_a_t\  BI  = M_A_CPU0_SA_DQS_DP<9>
  202  VSS87  POWER  = GND
  203  CB6_A  BI  = M_A_CPU0_SA_CB<6>
  204  VSS88  POWER  = GND
  205  CB7_A  BI  = M_A_CPU0_SA_CB<7>
  206  VSS89  POWER  = GND
  207  RESET_N  IN  = RST_M_AB_CPU0_FPGA_N
  208  VSS90  POWER  = GND
  209  CS1_A_N  IN  = M_A_CPU0_SA_CS_N<1>
  210  VSS91  POWER  = GND
  211  CA1_A  IN  = M_A_CPU0_SA_CA<1>
  212  VSS92  POWER  = GND
  213  CA3_A  IN  = M_A_CPU0_SA_CA<3>
  214  VSS93  POWER  = GND
  215  CA5_A  IN  = M_A_CPU0_SA_CA<5>
  216  VSS94  POWER  = GND
  217  CK_T  IN  = M_A_CPU0_CLK_DP<0>
  218  CK_C  IN  = M_A_CPU0_CLK_DN<0>
  219  VSS95  POWER  = GND
  220  RFU4  TRI  = TP_CHA_CPU0_DIMM1_FRU_4
  221  CA1_B  IN  = M_A_CPU0_SB_CA<1>
  222  VSS96  POWER  = GND
  223  CA3_B  IN  = M_A_CPU0_SB_CA<3>
  224  VSS97  POWER  = GND
  225  CA5_B  IN  = M_A_CPU0_SB_CA<5>
  226  VSS98  POWER  = GND
  227  PAR_B  IN  = M_A_CPU0_SB_PAR
  228  VSS99  POWER  = GND
  229  CS1_B_N  IN  = M_A_CPU0_SB_CS_N<1>
  230  VSS100  POWER  = GND
  231  RFU5  TRI  = TP_CHA_CPU0_DIMM1_FRU_5
  232  RFU6  TRI  = TP_CHA_CPU0_DIMM1_FRU_6
  233  VSS101  POWER  = GND
  234  CB6_B  BI  = M_A_CPU0_SB_CB<6>
  235  VSS102  POWER  = GND
  236  CB7_B  BI  = M_A_CPU0_SB_CB<7>
  237  VSS103  POWER  = GND
  238  DQS4_B_C  BI  = M_A_CPU0_SB_DQS_DN<4>
  239  DQS4_B_T  BI  = M_A_CPU0_SB_DQS_DP<4>
  240  VSS104  POWER  = GND
  241  CB2_B  BI  = M_A_CPU0_SB_CB<2>
  242  VSS105  POWER  = GND
  243  CB3_B  BI  = M_A_CPU0_SB_CB<3>
  244  VSS106  POWER  = GND
  245  DQ2_B  BI  = M_A_CPU0_SB_DQ<2>
  246  VSS107  POWER  = GND
  247  DQ3_B  BI  = M_A_CPU0_SB_DQ<3>
  248  VSS108  POWER  = GND
  249  \dqs5_b_c||tdqs5_b_c\  BI  = M_A_CPU0_SB_DQS_DN<5>
  250  \dqs5_b_t||tdqs5_b_t\  BI  = M_A_CPU0_SB_DQS_DP<5>
  251  VSS109  POWER  = GND
  252  DQ6_B  BI  = M_A_CPU0_SB_DQ<6>
  253  VSS110  POWER  = GND
  254  DQ7_B  BI  = M_A_CPU0_SB_DQ<7>
  255  VSS111  POWER  = GND
  256  DQ10_B  BI  = M_A_CPU0_SB_DQ<10>
  257  VSS112  POWER  = GND
  258  DQ11_B  BI  = M_A_CPU0_SB_DQ<11>
  259  VSS113  POWER  = GND
  260  \dqs6_b_c||tdqs6_b_c\  BI  = M_A_CPU0_SB_DQS_DN<6>
  261  \dqs6_b_t||tdqs6_b_t\  BI  = M_A_CPU0_SB_DQS_DP<6>
  262  VSS114  POWER  = GND
  263  DQ14_B  BI  = M_A_CPU0_SB_DQ<14>
  264  VSS115  POWER  = GND
  265  DQ15_B  BI  = M_A_CPU0_SB_DQ<15>
  266  VSS116  POWER  = GND
  267  DQ18_B  BI  = M_A_CPU0_SB_DQ<18>
  268  VSS117  POWER  = GND
  269  DQ19_B  BI  = M_A_CPU0_SB_DQ<19>
  270  VSS118  POWER  = GND
  271  \dqs7_b_c||tdqs7_b_c\  BI  = M_A_CPU0_SB_DQS_DN<7>
  272  \dqs7_b_t||tdqs7_b_t\  BI  = M_A_CPU0_SB_DQS_DP<7>
  273  VSS119  POWER  = GND
  274  DQ22_B  BI  = M_A_CPU0_SB_DQ<22>
  275  VSS120  POWER  = GND
  276  DQ23_B  BI  = M_A_CPU0_SB_DQ<23>
  277  VSS121  POWER  = GND
  278  DQ26_B  BI  = M_A_CPU0_SB_DQ<26>
  279  VSS122  POWER  = GND
  280  DQ27_B  BI  = M_A_CPU0_SB_DQ<27>
  281  VSS123  POWER  = GND
  282  \dqs8_b_c||tdqs8_b_c\  BI  = M_A_CPU0_SB_DQS_DN<8>
  283  \dqs8_b_t||tdqs8_b_t\  BI  = M_A_CPU0_SB_DQS_DP<8>
  284  VSS124  POWER  = GND
  285  DQ30_B  BI  = M_A_CPU0_SB_DQ<30>
  286  VSS125  POWER  = GND
  287  DQ31_B  BI  = M_A_CPU0_SB_DQ<31>
  288  VSS126  POWER  = GND
  G1  G1  POWER  = GND
  G2  G2  POWER  = GND
  G3  G3  POWER  = GND
